FILE_TYPE = CONNECTIVITY;
{Allegro Design Entry HDL 16.6-p007 (v16-6-112F) 10/10/2012}
"PAGE_NUMBER" = 226;
0"NC";
1"PVCCIO_CPU1\g";
2"GND\g";
3"GND\g";
4"GND\g";
5"GND\g";
6"GND\g";
7"GND\g";
8"GND\g";
9"GND\g";
10"P3V3_STBY\g";
11"GND\g";
12"GND\g";
13"P3V3_STBY\g";
14"PVCCIO_CPU1\g";
15"SVID_CLK_PVDDQ_KLM";
16"SVID_ALERT_PVDDQ_KLM";
17"VR_PVDDQ_KLM_VD12";
18"VR_PVDDQ_KLM_XADDR1";
19"NC_PVDDQ_KLM_GP1";
20"PU_VR_PVDDQ_KLM_FAULT1";
21"VR_PVDDQ_KLM_XADDR2";
22"SVID_VDIO_PVDDQ_KLM";
23"SMB_VR_STBY_LVC3_SCL";
24"SMB_VR_STBY_LVC3_SDA";
25"VR_PVDDQ_KLM_PWM2";
26"VR_PVDDQ_KLM_PWM1";
27"NC_PVDDQ_KLM_GP0";
28"PWRGD_PVDDQ_KLM";
29"SVID_DIO1_CPU1_R";
30"SVID_ALERT1_CPU1_R_N";
31"IRQ_PVDDQ_KLM_VRHOT_LVT3_N";
32"VR_PVDDQ_KLM_VD12";
33"VSENSE_PVDDQ_KLM_P";
34"FM_PVDDQ_KLM_EN";
35"VR_PVDDQ_KLM_VDD";
36"VSENSE_PVDDQ_KLM_N";
37"VR_PVDDQ_KLM_VINSEN";
38"SVID_CLK1_CPU1_R";
39"ISENSE_PVDDQ_KLM_PH1_IMON";
40"VR_PVDDQ_KLM_AIREF2";
41"ISENSE_PVDDQ_KLM_PH2_IMON";
42"VR_PVDDQ_KLM_AIREF1";
43"VR_PVDDQ_KLM_VREN";
44"VR_PVDDQ_KLM_AVSP";
45"A_TSENSE_PVDDQ_KLM";
46"VR_PVDDQ_KLM_AIINSEN";
47"IRQ_PVDDQ_KLM_VRHOT_LVT3_R_N";
48"PWRGD_PVDDQ_KLM_R";
%"CAP"
"1","(-1750,325)","0","mstr_discrete","I12";
;
VALUE"220PF"
TOLERANCE"10%"
PACK_TYPE"0402LF"
PART_NUMBER"A36096-050"
LOCATION"C1B12"
VOLTAGE"50V"
MATERIAL"X7R"
CDS_LIB"mstr_discrete"
CDS_LOCATION"C1B12"
SEC"1"
NO_XNET_CONNECTION"1"
ROOM"VDDQ_KLM_PWR_VR"
SEC_TYPE"0402LF"
CDS_SEC"1";
"A"
$PN"1"44;
"B"
$PN"2"36;
%"RES"
"1","(-1925,475)","0","mstr_discrete","I13";
;
LOCATION"R1B16"
PART_NUMBER"G21796-066"
PACK_TYPE"0402"
MATERIAL"CHIP"
TOLERANCE"1%"
VALUE"10.0"
WATTAGE"1/16W"
NO_XNET_CONNECTION"1"
SEC"1"
SEC_TYPE"0402"
ROOM"VDDQ_KLM_PWR_VR"
CDS_LOCATION"R1B16"
CDS_LIB"mstr_discrete"
CDS_SEC"1";
"B"
$PN"2"44;
"A"
$PN"1"33;
%"RES"
"1","(-1800,775)","0","mstr_discrete","I14";
;
PART_NUMBER"G21497-005"
TOLERANCE"5%"
PACK_TYPE"0402"
LOCATION"R9M9"
MATERIAL"CHIP"
WATTAGE"1/16W"
VALUE"0.0"
CDS_SEC"1"
$SEC"1"
ROOM"PVCCIN_CPU0_VR"
CDS_LOCATION"R9M9"
CDS_LIB"mstr_discrete";
"B"
$PN"2"43;
"A"
$PN"1"34;
%"SC22P50V2JN-4GP"
"1","(-1550,1850)","1","w_hdl","I15";
;
GROUP"POWER_FAIR"
VALUE"SC22P50V2JN-4GP"
PACK_SIZE"0402"
TOLERANCE"5%"
RATED"50V"
TYPE"NPO"
ATTRIBUTE"22PF"
LOCATION"CF21"
CDS_SEC"1"
$SEC"1"
CDS_LOCATION"CF21"
CDS_LIB"w_hdl"
CDS_LMAN_SYM_OUTLINE"-50,25,50,-25"
PACK_TYPE"SMD-BCG"
PART_NUMBER"78.22034.1FL";
"2"
$PN"2"39;
"1"
$PN"1"42;
%"RES"
"1","(-1550,2025)","0","mstr_discrete","I16";
;
GROUP"POWER_FAIR"
WATTAGE"1/16W"
TOLERANCE"0.1%"
PART_NUMBER"G85996-004"
LOCATION"RF21"
VALUE"1.0K"
PACK_TYPE"0402"
MATERIAL"CHIP"
FAIR_SS"064.9090D.M001"
CDS_SEC"1"
CDS_LOCATION"RF21"
CDS_LIB"mstr_discrete"
ROOM"SB"
SEC"1"
SEC_TYPE"0402";
"B"
$PN"2"39;
"A"
$PN"1"42;
%"SC22P50V2JN-4GP"
"1","(-750,1850)","1","w_hdl","I17";
;
LOCATION"CF22"
ATTRIBUTE"22PF"
PACK_SIZE"0402"
BOM_SS"NOPOP"
RATED"50V"
TOLERANCE"5%"
TYPE"NPO"
GROUP"POWER_FAIR"
VALUE"SC22P50V2JN-4GP"
CDS_SEC"1"
$SEC"1"
CDS_LOCATION"CF22"
CDS_LIB"w_hdl"
CDS_LMAN_SYM_OUTLINE"-50,25,50,-25"
PART_NUMBER"78.22034.1FL"
PACK_TYPE"SMD-BCG";
"2"
$PN"2"41;
"1"
$PN"1"40;
%"RES"
"1","(-775,2025)","0","mstr_discrete","I18";
;
PART_NUMBER"G85996-004"
PACK_TYPE"0402"
WATTAGE"1/16W"
MATERIAL"CHIP"
TOLERANCE"0.1%"
VALUE"1.0K"
LOCATION"RF22"
GROUP"POWER_FAIR"
BOM_SS"NOPOP"
SEC_TYPE"0402"
SEC"1"
ROOM"SB"
CDS_LIB"mstr_discrete"
CDS_LOCATION"RF22"
CDS_SEC"1";
"B"
$PN"2"41;
"A"
$PN"1"40;
%"RES"
"1","(-550,2350)","0","mstr_discrete","I19";
;
MATERIAL"CHIP"
WATTAGE"1/16W"
VALUE"150.0"
PART_NUMBER"G21796-009"
LOCATION"R1B8"
TOLERANCE"1%"
PACK_TYPE"0402"
CDS_LOCATION"R1B8"
ROOM"VDDQ_KLM_PWR_VR"
SEC"1"
SEC_TYPE"0402"
CDS_LIB"mstr_discrete"
CDS_SEC"1";
"B"
$PN"2"15;
"A"
$PN"1"38;
%"PVCCIO_CPU1"
"1","(-925,3200)","0","mstr_symbols","I21";
;
CDS_LIB"mstr_symbols"
VOLTAGE"1.1V"
BODY_TYPE"PLUMBING"
HDL_POWER"PVCCIO_CPU1";
"G\NAC"1;
%"GND"
"1","(-225,-675)","0","mstr_symbols","I22";
;
ROOM"VDDQ_KLM_PWR_VR"
SIZE"1B"
CDS_LIB"mstr_symbols"
VOLTAGE"0"
BODY_TYPE"PLUMBING"
HDL_POWER"GND";
"A\NAC"2;
%"CAP"
"1","(-225,25)","2","mstr_discrete","I23";
;
VOLTAGE"50V"
MATERIAL"X7R"
TOLERANCE"10%"
PACK_TYPE"0402LF"
PART_NUMBER"A36096-050"
LOCATION"C1B11"
VALUE"220PF"
SEC_TYPE"0402LF"
SEC"1"
CDS_LOCATION"C1B11"
ROOM"VDDQ_KLM_PWR_VR"
CDS_LIB"mstr_discrete"
CDS_SEC"1";
"A"
$PN"1"45;
"B"
$PN"2"2;
%"GND"
"1","(3100,-750)","0","mstr_symbols","I24";
;
ROOM"VDDQ_KLM_PWR_VR"
VOLTAGE"0"
CDS_LIB"mstr_symbols"
SIZE"1B"
BODY_TYPE"PLUMBING"
HDL_POWER"GND";
"A\NAC"3;
%"GND"
"1","(3500,-750)","0","mstr_symbols","I25";
;
VOLTAGE"0"
SIZE"1B"
CDS_LIB"mstr_symbols"
ROOM"VDDQ_KLM_PWR_VR"
BODY_TYPE"PLUMBING"
HDL_POWER"GND";
"A\NAC"4;
%"GND"
"1","(-50,-850)","0","mstr_symbols","I26";
;
CDS_LIB"mstr_symbols"
VOLTAGE"0"
SIZE"1B"
ROOM"VDDQ_KLM_PWR_VR"
BODY_TYPE"PLUMBING"
HDL_POWER"GND";
"A\NAC"5;
%"GND"
"1","(-150,125)","0","mstr_symbols","I28";
;
ROOM"VDDQ_KLM_PWR_VR"
VOLTAGE"0"
CDS_LIB"mstr_symbols"
SIZE"1B"
BODY_TYPE"PLUMBING"
HDL_POWER"GND";
"A\NAC"6;
%"GND"
"1","(325,-850)","0","mstr_symbols","I29";
;
CDS_LIB"mstr_symbols"
VOLTAGE"0"
SIZE"1B"
ROOM"VDDQ_KLM_PWR_VR"
BODY_TYPE"PLUMBING"
HDL_POWER"GND";
"A\NAC"7;
%"GND"
"1","(1750,100)","0","mstr_symbols","I31";
;
ROOM"VDDQ_KLM_PWR_VR"
CDS_LIB"mstr_symbols"
VOLTAGE"0"
SIZE"1B"
BODY_TYPE"PLUMBING"
HDL_POWER"GND";
"A\NAC"8;
%"CAP_A"
"1","(675,2375)","0","dev_discrete","I32";
;
VALUE"0.1UF"
LOCATION"C1B5"
PACK_TYPE"0402V"
VOLTAGE"16V"
MATERIAL"X7R"
TOLERANCE"10%"
PART_NUMBER"A36096-030"
CDS_LIB"dev_discrete"
CDS_SEC"1"
ROOM"VDDQ_KLM_PWR_VR"
CDS_LOCATION"C1B5"
SEC"1"
SEC_TYPE"0402V";
"B"
$PN"2"9;
"A"
$PN"1"35;
%"GND"
"1","(675,2175)","0","mstr_symbols","I33";
;
ROOM"VDDQ_KLM_PWR_VR"
VOLTAGE"0"
CDS_LIB"mstr_symbols"
SIZE"1B"
BODY_TYPE"PLUMBING"
HDL_POWER"GND";
"A\NAC"9;
%"RES"
"2","(-175,2850)","0","mstr_discrete","I34";
;
WATTAGE"1/16W"
MATERIAL"EMPTY"
VALUE"100.0K"
PACK_TYPE"0402"
TOLERANCE"1%"
PART_NUMBER"G21796-010"
LOCATION"R9M5"
CDS_LIB"mstr_discrete"
CDS_LOCATION"R9M5"
ROOM"BMC"
SEC"1"
SEC_TYPE"0402"
BOM_COST"SM_CONTROLLER"
CDS_SEC"1";
"A"
$PN"1"10;
"B"
$PN"2"43;
%"P3V3_STBY"
"1","(250,3200)","0","mstr_symbols","I35";
;
SIZE"1B"
VOLTAGE"3.3V"
CDS_LIB"mstr_symbols"
BODY_TYPE"PLUMBING"
HDL_POWER"P3V3_STBY";
"G\NAC"10;
%"RES"
"2","(575,2825)","0","mstr_discrete","I36";
;
MATERIAL"CHIP"
WATTAGE"1/16W"
PACK_TYPE"0402"
LOCATION"R9M3"
TOLERANCE"5%"
VALUE"0.0"
PART_NUMBER"G21497-005"
CDS_LIB"mstr_discrete"
ROOM"VDDQ_KLM_PWR_VR"
CDS_LOCATION"R9M3"
SEC_TYPE"0402"
SEC"1"
CDS_SEC"1";
"A"
$PN"1"10;
"B"
$PN"2"35;
%"GND"
"1","(1275,2175)","0","mstr_symbols","I37";
;
ROOM"VDDQ_KLM_PWR_VR"
CDS_LIB"mstr_symbols"
VOLTAGE"0"
SIZE"1B"
BODY_TYPE"PLUMBING"
HDL_POWER"GND";
"A\NAC"11;
%"CAP_A"
"1","(1275,2375)","0","dev_discrete","I38";
;
PART_NUMBER"D97712-004"
PACK_TYPE"0402V"
LOCATION"C1B6"
VALUE"1.0UF"
MATERIAL"X6S"
VOLTAGE"6.3V"
TOLERANCE"10%"
SEC_TYPE"0402V"
SEC"1"
CDS_LIB"dev_discrete"
ROOM"VDDQ_KLM_PWR_VR"
CDS_LOCATION"C1B6"
CDS_SEC"1";
"B"
$PN"2"11;
"A"
$PN"1"35;
%"GND"
"1","(2650,0)","0","mstr_symbols","I39";
;
ROOM"VDDQ_KLM_PWR_VR"
VOLTAGE"0"
CDS_LIB"mstr_symbols"
SIZE"1B"
BODY_TYPE"PLUMBING"
HDL_POWER"GND";
"A\NAC"12;
%"CAP"
"1","(2650,275)","0","mstr_discrete","I40";
;
PART_NUMBER"A36096-046"
MATERIAL"X7R"
TOLERANCE"10%"
LOCATION"C1B4"
VOLTAGE"50V"
VALUE"1000PF"
PACK_TYPE"0402LF"
CDS_LIB"mstr_discrete"
ROOM"VDDQ_KLM_PWR_VR"
CDS_LOCATION"C1B4"
SEC"1"
SEC_TYPE"0402LF"
CDS_SEC"1";
"A"
$PN"1"48;
"B"
$PN"2"12;
%"RES"
"1","(2525,975)","0","mstr_discrete","I41";
;
WATTAGE"1/16W"
TOLERANCE"5%"
PACK_TYPE"0402"
VALUE"0.0"
PART_NUMBER"G21497-005"
LOCATION"R1B10"
MATERIAL"CHIP"
SEC"1"
SEC_TYPE"0402"
ROOM"VDDQ_KLM_PWR_VR"
CDS_LIB"mstr_discrete"
CDS_LOCATION"R1B10"
CDS_SEC"1";
"B"
$PN"2"29;
"A"
$PN"1"22;
%"CAP_A"
"1","(3100,-525)","0","dev_discrete","I44";
;
PART_NUMBER"A36096-030"
LOCATION"C1B2"
VALUE"0.1UF"
MATERIAL"X7R"
PACK_TYPE"0402V"
VOLTAGE"16V"
TOLERANCE"10%"
CDS_LIB"dev_discrete"
ROOM"VDDQ_KLM_PWR_VR"
CDS_LOCATION"C1B2"
CDS_SEC"1"
SEC_TYPE"0402V"
SEC"1";
"B"
$PN"2"3;
"A"
$PN"1"32;
%"CAP_A"
"1","(3500,-525)","0","dev_discrete","I45";
;
PACK_TYPE"0402V"
LOCATION"C1B3"
VOLTAGE"6.3V"
VALUE"1.0UF"
MATERIAL"X6S"
PART_NUMBER"D97712-004"
TOLERANCE"10%"
ROOM"VDDQ_KLM_PWR_VR"
SEC"1"
SEC_TYPE"0402V"
CDS_SEC"1"
CDS_LOCATION"C1B3"
CDS_LIB"dev_discrete";
"B"
$PN"2"4;
"A"
$PN"1"32;
%"RES"
"1","(2950,1125)","0","mstr_discrete","I46";
;
WATTAGE"1/16W"
PACK_TYPE"0402"
VALUE"0.0"
LOCATION"R12W35"
PART_NUMBER"G21497-005"
MATERIAL"EMPTY"
TOLERANCE"5%"
CDS_LIB"mstr_discrete"
SEC"1"
ROOM"NV_DIMM"
SEC_TYPE"0402"
BOM_COST"MEM_NV"
CDS_LOCATION"R12W35"
CDS_SEC"1";
"B"
$PN"2"28;
"A"
$PN"1"19;
%"RES"
"1","(2325,1675)","0","mstr_discrete","I48";
;
MATERIAL"CHIP"
PACK_TYPE"0402"
PART_NUMBER"G21497-005"
TOLERANCE"5%"
VALUE"0.0"
WATTAGE"1/16W"
LOCATION"R1B11"
CDS_LOCATION"R1B11"
CDS_LIB"mstr_discrete"
SEC"1"
SEC_TYPE"0402"
ROOM"VDDQ_KLM_PWR_VR"
CDS_SEC"1";
"B"
$PN"2"30;
"A"
$PN"1"16;
%"RES"
"2","(1825,2350)","0","mstr_discrete","I49";
;
TOLERANCE"1%"
PACK_TYPE"0402"
PART_NUMBER"G21796-026"
MATERIAL"CHIP"
WATTAGE"1/16W"
VALUE"1.00K"
LOCATION"R1B1"
CDS_LOCATION"R1B1"
CDS_LIB"mstr_discrete"
SEC_TYPE"0402"
SEC"1"
ROOM"RQ_PVDDQ_KLM_VRHOT_LVT3_N"
CDS_SEC"1";
"A"
$PN"1"13;
"B"
$PN"2"47;
%"RES"
"2","(2100,2350)","0","mstr_discrete","I50";
;
VALUE"1.00K"
WATTAGE"1/16W"
TOLERANCE"1%"
MATERIAL"CHIP"
LOCATION"R1B2"
PACK_TYPE"0402"
PART_NUMBER"G21796-026"
SEC_TYPE"0402"
CDS_LOCATION"R1B2"
SEC"1"
ROOM"VDDQ_KLM_PWR_VR"
CDS_LIB"mstr_discrete"
CDS_SEC"1";
"A"
$PN"1"13;
"B"
$PN"2"48;
%"P3V3_STBY"
"1","(2200,3000)","0","mstr_symbols","I52";
;
CDS_LIB"mstr_symbols"
SIZE"1B"
VOLTAGE"3.3V"
BODY_TYPE"PLUMBING"
HDL_POWER"P3V3_STBY";
"G\NAC"13;
%"RES"
"1","(2950,1525)","0","mstr_discrete","I53";
;
PART_NUMBER"G21497-005"
TOLERANCE"5%"
LOCATION"R12W36"
VALUE"0.0"
PACK_TYPE"0402"
MATERIAL"EMPTY"
WATTAGE"1/16W"
CDS_LIB"mstr_discrete"
SEC"1"
ROOM"NV_DIMM"
SEC_TYPE"0402"
BOM_COST"MEM_NV"
CDS_LOCATION"R12W36"
CDS_SEC"1";
"B"
$PN"2"28;
"A"
$PN"1"27;
%"RES"
"1","(3025,1725)","0","mstr_discrete","I54";
;
TOLERANCE"1%"
PACK_TYPE"0402"
MATERIAL"CHIP"
LOCATION"R1B4"
VALUE"33.2"
WATTAGE"1/16W"
PART_NUMBER"G21796-074"
SEC_TYPE"0402"
SEC"1"
CDS_LIB"mstr_discrete"
CDS_LOCATION"R1B4"
CDS_SEC"1";
"B"
$PN"2"31;
"A"
$PN"1"47;
%"RES"
"1","(3025,1825)","0","mstr_discrete","I55";
;
PACK_TYPE"0402"
PART_NUMBER"G21796-250"
MATERIAL"CHIP"
WATTAGE"1/16W"
VALUE"22.1"
LOCATION"R1B5"
TOLERANCE"1.0%"
POP"NOPOP"
CDS_LIB"mstr_discrete"
ROOM"VDDQ_KLM_PWR_VR"
CDS_LOCATION"R1B5"
SEC"1"
SEC_TYPE"0402"
CDS_SEC"1";
"B"
$PN"2"28;
"A"
$PN"1"48;
%"RES"
"2","(3750,2075)","0","mstr_discrete","I57";
;
LOCATION"R9M7"
VALUE"100.0"
PACK_TYPE"0402"
PART_NUMBER"G21796-017"
MATERIAL"EMPTY"
WATTAGE"1/16W"
TOLERANCE"1%"
CDS_SEC"1"
SEC_TYPE"0402"
SEC"1"
CDS_LOCATION"R9M7"
ROOM"VDDQ_KLM_PWR_VR"
CDS_LIB"mstr_discrete";
"A"
$PN"1"14;
"B"
$PN"2"29;
%"PVCCIO_CPU1"
"1","(3750,2300)","0","mstr_symbols","I58";
;
VOLTAGE"1.1V"
CDS_LIB"mstr_symbols"
BODY_TYPE"PLUMBING"
HDL_POWER"PVCCIO_CPU1";
"G\NAC"14;
%"PXM1310B"
"2","(1175,1075)","0","mstr_controller","I69";
;
PART_NUMBER"H89186-001"
MATERIAL"IC"
LOCATION"EU1B1"
CDS_SEC"1"
SEC"1"
SEC_TYPE"QFN"
PACK_TYPE"QFN"
CDS_LOCATION"EU1B1"
CDS_LIB"mstr_controller"
CDS_LMAN_SYM_OUTLINE"-400,900,400,-900";
"MP2"
$PN"18"27;
"THPAD"
$PN"41"8;
"BPWM1"
$PN"1"0;
"APWM1"
$PN"5"26;
"APWM2"
$PN"4"25;
"APWM3"
$PN"3"0;
"SDA"
$PN"6"24;
"SCL"
$PN"7"23;
"VCLK"
$PN"15"15;
"VDIO"
$PN"16"22;
"RESET_N \B"
$PN"8"0;
"XADDR1"
$PN"36"18;
"AISEN3"
$PN"26"0;
"AIREF3"
$PN"25"0;
"XADDR2"
$PN"33"21;
"AISEN2"
$PN"24"41;
"AIREF2"
$PN"23"40;
"ATSEN"
$PN"35"45;
"AISEN1"
$PN"22"39;
"AIREF1"
$PN"21"42;
"VDD"
$PN"39"35;
"BTSEN"
$PN"34"0;
"BISEN1"
$PN"32"6;
"BIREF1"
$PN"31"0;
"DNC<0>"
$PN"2"0;
"DNC<1>"
$PN"28"0;
"VRHOT_N \B"
$PN"11"47;
"PINALRT_N \B"
$PN"12"0;
"VALRT_N \B"
$PN"17"16;
"AVSEN"
$PN"19"44;
"AVREF"
$PN"20"36;
"BVSEN"
$PN"29"0;
"BVREF"
$PN"30"0;
"VINSEN"
$PN"37"37;
"VD12"
$PN"40"17;
"GND"
$PN"27"8;
"IINSEN"
$PN"38"46;
"AVRRDY"
$PN"9"48;
"AVREN"
$PN"10"43;
"MP0"
$PN"13"20;
"MP1"
$PN"14"19;
%"RES"
"2","(-925,2850)","0","mstr_discrete","I70";
;
PACK_TYPE"0402"
LOCATION"R9M6"
VALUE"49.9"
PART_NUMBER"G21796-047"
TOLERANCE"1%"
MATERIAL"EMPTY"
WATTAGE"1/16W"
SEC_TYPE"0402"
SEC"1"
ROOM"VDDQ_GHJ_PWR_VR"
CDS_LIB"mstr_discrete"
CDS_SEC"1"
CDS_LOCATION"R9M6";
"A"
$PN"1"1;
"B"
$PN"2"38;
%"RES"
"2","(-50,-600)","0","mstr_discrete","I72";
;
CDS_SEC"1"
$SEC"1"
CDS_LOCATION"R1B12"
LOCATION"R1B12"
TOLERANCE"1.0%"
VALUE"16K"
PACK_TYPE"0402"
PART_NUMBER"G21796-317"
WATTAGE"1/16W"
MATERIAL"CHIP"
ROOM"VDDQ_ABC_PWR_VR"
CDS_LIB"mstr_discrete";
"A"
$PN"1"18;
"B"
$PN"2"5;
%"RES"
"2","(325,-600)","0","mstr_discrete","I73";
;
PART_NUMBER"G21796-043"
PACK_TYPE"0402"
TOLERANCE"1%"
MATERIAL"CHIP"
WATTAGE"1/16W"
VALUE"3.16K"
LOCATION"R1B15"
CDS_LOCATION"R1B15"
SEC_TYPE"0402"
SEC"1"
ROOM"PVCCIN_CPU1_VR"
CDS_LIB"mstr_discrete"
CDS_SEC"1";
"A"
$PN"1"21;
"B"
$PN"2"7;
%"RES"
"1","(2950,1175)","0","mstr_discrete","I74";
;
PACK_TYPE"0402"
LOCATION"R12W34"
VALUE"0.0"
TOLERANCE"5%"
WATTAGE"1/16W"
PART_NUMBER"G21497-005"
SEC"1"
SEC_TYPE"0402"
ROOM"CPU0"
MATERIAL"CHIP"
BOM_COST"PROC_SIDEBAND"
CDS_LIB"mstr_discrete"
CDS_SEC"1"
CDS_LOCATION"R12W34";
"B"
$PN"2"28;
"A"
$PN"1"20;
%"RES"
"2","(3250,2350)","0","mstr_discrete","I75";
;
CDS_SEC"1"
$SEC"1"
CDS_LOCATION"R1B13"
VALUE"2.26K"
TOLERANCE"1.0%"
WATTAGE"1/16W"
MATERIAL"CHIP"
LOCATION"R1B13"
PACK_TYPE"0402"
PART_NUMBER"G21796-311"
SKU"B"
ROOM"SMBUS"
BOM_COST"SM_CONTROLLER"
CDS_LIB"mstr_discrete";
"A"
$PN"1"13;
"B"
$PN"2"28;
END.
